(kicad_pcb
	(version 20260206)
	(generator "pcbnew")
	(generator_version "10.0")
	(general
		(thickness 1.6)
		(legacy_teardrops no)
	)
	(paper "A4")
	(title_block
		(title "12092022_DA0F0TMDCD0_F0T_Management_Board_D_brd_V3_OCP.brd")
		(comment 1 "Grand Teton / footprints 1263-1268 of 1440")
	)
	(layers
		(0 "F.Cu" signal "TOP")
		(4 "In1.Cu" signal "GND")
		(6 "In2.Cu" signal "IN1")
		(8 "In3.Cu" signal "GND1")
		(10 "In4.Cu" signal "IN2")
		(12 "In5.Cu" signal "VCC")
		(14 "In6.Cu" signal "VCC1")
		(16 "In7.Cu" signal "IN3")
		(18 "In8.Cu" signal "GND2")
		(20 "In9.Cu" signal "IN4")
		(22 "In10.Cu" signal "GND3")
		(2 "B.Cu" signal "BOTTOM")
		(9 "F.Adhes" user "F.Adhesive")
		(11 "B.Adhes" user "B.Adhesive")
		(13 "F.Paste" user "Package Geometry/Pastemask Top")
		(15 "B.Paste" user "Package Geometry/Pastemask Bottom")
		(5 "F.SilkS" user "Ref Des/Silkscreen Top")
		(7 "B.SilkS" user "Ref Des/Silkscreen Bottom")
		(1 "F.Mask" user "Board Geometry/Soldermask Top")
		(3 "B.Mask" user "Board Geometry/Soldermask Bottom")
		(17 "Dwgs.User" user "User.Drawings")
		(19 "Cmts.User" user "User.Comments")
		(21 "Eco1.User" user "User.Eco1")
		(23 "Eco2.User" user "User.Eco2")
		(25 "Edge.Cuts" user "Board Geometry/Outline")
		(27 "Margin" user)
		(31 "F.CrtYd" user "Package Geometry/Place Bound Top")
		(29 "B.CrtYd" user "Package Geometry/Place Bound Bottom")
		(35 "F.Fab" user "Ref Des/Assembly Top")
		(33 "B.Fab" user "Ref Des/Assembly Bottom")
	)
	(footprint ""
		(layer "B.Cu")
		(at 20.955 -101.981 -90)
		(property "Reference" "R749"
			(at 0 0 90)
			(layer "B.SilkS")
			(hide yes)
			(effects
				(font
					(size 1.27 1.27)
				)
				(justify mirror)
			)
		)
		(property "Value" ""
			(at 0 0 90)
			(layer "B.Fab")
			(effects
				(font
					(size 1.27 1.27)
				)
				(justify mirror)
			)
		)
		(duplicate_pad_numbers_are_jumpers no)
		(fp_line
			(start -0.7874 0.4064)
			(end 0.7874 0.4064)
			(stroke
				(width 0.1524)
				(type default)
			)
			(layer "B.SilkS")
		)
		(fp_line
			(start 0.7874 0.4064)
			(end 0.7874 -0.4064)
			(stroke
				(width 0.1524)
				(type default)
			)
			(layer "B.SilkS")
		)
		(fp_line
			(start -0.7874 -0.4064)
			(end -0.7874 0.4064)
			(stroke
				(width 0.1524)
				(type default)
			)
			(layer "B.SilkS")
		)
		(fp_line
			(start 0.7874 -0.4064)
			(end -0.7874 -0.4064)
			(stroke
				(width 0.1524)
				(type default)
			)
			(layer "B.SilkS")
		)
		(fp_line
			(start -0.67945 0.3048)
			(end -0.120396 0.3048)
			(stroke
				(width 0.1)
				(type default)
			)
			(layer "B.Fab")
		)
		(fp_line
			(start -0.120396 0.3048)
			(end -0.120396 0.2794)
			(stroke
				(width 0.1)
				(type default)
			)
			(layer "B.Fab")
		)
		(fp_line
			(start 0.12065 0.3048)
			(end 0.67945 0.3048)
			(stroke
				(width 0.1)
				(type default)
			)
			(layer "B.Fab")
		)
		(fp_line
			(start 0.67945 0.3048)
			(end 0.67945 -0.305054)
			(stroke
				(width 0.1)
				(type default)
			)
			(layer "B.Fab")
		)
		(fp_line
			(start -0.120396 0.2794)
			(end 0.12065 0.2794)
			(stroke
				(width 0.1)
				(type default)
			)
			(layer "B.Fab")
		)
		(fp_line
			(start 0.12065 0.2794)
			(end 0.12065 0.3048)
			(stroke
				(width 0.1)
				(type default)
			)
			(layer "B.Fab")
		)
		(fp_line
			(start -0.12065 -0.2794)
			(end -0.12065 -0.3048)
			(stroke
				(width 0.1)
				(type default)
			)
			(layer "B.Fab")
		)
		(fp_line
			(start 0.12065 -0.2794)
			(end -0.12065 -0.2794)
			(stroke
				(width 0.1)
				(type default)
			)
			(layer "B.Fab")
		)
		(fp_line
			(start -0.67945 -0.3048)
			(end -0.67945 0.3048)
			(stroke
				(width 0.1)
				(type default)
			)
			(layer "B.Fab")
		)
		(fp_line
			(start -0.12065 -0.3048)
			(end -0.67945 -0.3048)
			(stroke
				(width 0.1)
				(type default)
			)
			(layer "B.Fab")
		)
		(fp_line
			(start 0.12065 -0.305054)
			(end 0.12065 -0.2794)
			(stroke
				(width 0.1)
				(type default)
			)
			(layer "B.Fab")
		)
		(fp_line
			(start 0.67945 -0.305054)
			(end 0.12065 -0.305054)
			(stroke
				(width 0.1)
				(type default)
			)
			(layer "B.Fab")
		)
		(pad "1" smd circle
			(at 0.40005 0 90)
			(size 0 0)
			(layers "B.Cu" "B.Mask" "B.Paste")
			(net "P3V3_AUX")
		)
		(pad "2" smd circle
			(at -0.40005 0 90)
			(size 0 0)
			(layers "B.Cu" "B.Mask" "B.Paste")
			(net "FM_BMC_CRASHLOG_TRIG_N")
		)
	)
	(footprint ""
		(layer "B.Cu")
		(at 78.02372 -51.000406 180)
		(property "Reference" "R3"
			(at 0 0 0)
			(layer "B.SilkS")
			(hide yes)
			(effects
				(font
					(size 1.27 1.27)
				)
				(justify mirror)
			)
		)
		(property "Value" ""
			(at 0 0 0)
			(layer "B.Fab")
			(effects
				(font
					(size 1.27 1.27)
				)
				(justify mirror)
			)
		)
		(duplicate_pad_numbers_are_jumpers no)
		(fp_line
			(start 0.7874 0.4064)
			(end 0.7874 -0.4064)
			(stroke
				(width 0.1524)
				(type default)
			)
			(layer "B.SilkS")
		)
		(fp_line
			(start 0.7874 -0.4064)
			(end -0.7874 -0.4064)
			(stroke
				(width 0.1524)
				(type default)
			)
			(layer "B.SilkS")
		)
		(fp_line
			(start -0.7874 0.4064)
			(end 0.7874 0.4064)
			(stroke
				(width 0.1524)
				(type default)
			)
			(layer "B.SilkS")
		)
		(fp_line
			(start -0.7874 -0.4064)
			(end -0.7874 0.4064)
			(stroke
				(width 0.1524)
				(type default)
			)
			(layer "B.SilkS")
		)
		(fp_line
			(start 0.67945 0.3048)
			(end 0.67945 -0.305054)
			(stroke
				(width 0.1)
				(type default)
			)
			(layer "B.Fab")
		)
		(fp_line
			(start 0.67945 -0.305054)
			(end 0.12065 -0.305054)
			(stroke
				(width 0.1)
				(type default)
			)
			(layer "B.Fab")
		)
		(fp_line
			(start 0.12065 0.3048)
			(end 0.67945 0.3048)
			(stroke
				(width 0.1)
				(type default)
			)
			(layer "B.Fab")
		)
		(fp_line
			(start 0.12065 0.2794)
			(end 0.12065 0.3048)
			(stroke
				(width 0.1)
				(type default)
			)
			(layer "B.Fab")
		)
		(fp_line
			(start 0.12065 -0.2794)
			(end -0.12065 -0.2794)
			(stroke
				(width 0.1)
				(type default)
			)
			(layer "B.Fab")
		)
		(fp_line
			(start 0.12065 -0.305054)
			(end 0.12065 -0.2794)
			(stroke
				(width 0.1)
				(type default)
			)
			(layer "B.Fab")
		)
		(fp_line
			(start -0.120396 0.3048)
			(end -0.120396 0.2794)
			(stroke
				(width 0.1)
				(type default)
			)
			(layer "B.Fab")
		)
		(fp_line
			(start -0.120396 0.2794)
			(end 0.12065 0.2794)
			(stroke
				(width 0.1)
				(type default)
			)
			(layer "B.Fab")
		)
		(fp_line
			(start -0.12065 -0.2794)
			(end -0.12065 -0.3048)
			(stroke
				(width 0.1)
				(type default)
			)
			(layer "B.Fab")
		)
		(fp_line
			(start -0.12065 -0.3048)
			(end -0.67945 -0.3048)
			(stroke
				(width 0.1)
				(type default)
			)
			(layer "B.Fab")
		)
		(fp_line
			(start -0.67945 0.3048)
			(end -0.120396 0.3048)
			(stroke
				(width 0.1)
				(type default)
			)
			(layer "B.Fab")
		)
		(fp_line
			(start -0.67945 -0.3048)
			(end -0.67945 0.3048)
			(stroke
				(width 0.1)
				(type default)
			)
			(layer "B.Fab")
		)
		(pad "1" smd circle
			(at 0.40005 0)
			(size 0 0)
			(layers "B.Cu" "B.Mask" "B.Paste")
			(net "M_BMC_DDR4_ZQU")
		)
		(pad "2" smd circle
			(at -0.40005 0)
			(size 0 0)
			(layers "B.Cu" "B.Mask" "B.Paste")
			(net "GND")
		)
	)
	(footprint ""
		(layer "B.Cu")
		(at 59.7154 -64.3382 -90)
		(property "Reference" "R176"
			(at 0 0 90)
			(layer "B.SilkS")
			(hide yes)
			(effects
				(font
					(size 1.27 1.27)
				)
				(justify mirror)
			)
		)
		(property "Value" ""
			(at 0 0 90)
			(layer "B.Fab")
			(effects
				(font
					(size 1.27 1.27)
				)
				(justify mirror)
			)
		)
		(duplicate_pad_numbers_are_jumpers no)
		(fp_line
			(start -0.7874 0.4064)
			(end 0.7874 0.4064)
			(stroke
				(width 0.1524)
				(type default)
			)
			(layer "B.SilkS")
		)
		(fp_line
			(start 0.7874 0.4064)
			(end 0.7874 -0.4064)
			(stroke
				(width 0.1524)
				(type default)
			)
			(layer "B.SilkS")
		)
		(fp_line
			(start -0.7874 -0.4064)
			(end -0.7874 0.4064)
			(stroke
				(width 0.1524)
				(type default)
			)
			(layer "B.SilkS")
		)
		(fp_line
			(start 0.7874 -0.4064)
			(end -0.7874 -0.4064)
			(stroke
				(width 0.1524)
				(type default)
			)
			(layer "B.SilkS")
		)
		(fp_line
			(start -0.67945 0.3048)
			(end -0.120396 0.3048)
			(stroke
				(width 0.1)
				(type default)
			)
			(layer "B.Fab")
		)
		(fp_line
			(start -0.120396 0.3048)
			(end -0.120396 0.2794)
			(stroke
				(width 0.1)
				(type default)
			)
			(layer "B.Fab")
		)
		(fp_line
			(start 0.12065 0.3048)
			(end 0.67945 0.3048)
			(stroke
				(width 0.1)
				(type default)
			)
			(layer "B.Fab")
		)
		(fp_line
			(start 0.67945 0.3048)
			(end 0.67945 -0.305054)
			(stroke
				(width 0.1)
				(type default)
			)
			(layer "B.Fab")
		)
		(fp_line
			(start -0.120396 0.2794)
			(end 0.12065 0.2794)
			(stroke
				(width 0.1)
				(type default)
			)
			(layer "B.Fab")
		)
		(fp_line
			(start 0.12065 0.2794)
			(end 0.12065 0.3048)
			(stroke
				(width 0.1)
				(type default)
			)
			(layer "B.Fab")
		)
		(fp_line
			(start -0.12065 -0.2794)
			(end -0.12065 -0.3048)
			(stroke
				(width 0.1)
				(type default)
			)
			(layer "B.Fab")
		)
		(fp_line
			(start 0.12065 -0.2794)
			(end -0.12065 -0.2794)
			(stroke
				(width 0.1)
				(type default)
			)
			(layer "B.Fab")
		)
		(fp_line
			(start -0.67945 -0.3048)
			(end -0.67945 0.3048)
			(stroke
				(width 0.1)
				(type default)
			)
			(layer "B.Fab")
		)
		(fp_line
			(start -0.12065 -0.3048)
			(end -0.67945 -0.3048)
			(stroke
				(width 0.1)
				(type default)
			)
			(layer "B.Fab")
		)
		(fp_line
			(start 0.12065 -0.305054)
			(end 0.12065 -0.2794)
			(stroke
				(width 0.1)
				(type default)
			)
			(layer "B.Fab")
		)
		(fp_line
			(start 0.67945 -0.305054)
			(end 0.12065 -0.305054)
			(stroke
				(width 0.1)
				(type default)
			)
			(layer "B.Fab")
		)
		(pad "1" smd circle
			(at 0.40005 0 90)
			(size 0 0)
			(layers "B.Cu" "B.Mask" "B.Paste")
			(net "SPI_BMC_BIOS_ROM_MISO")
		)
		(pad "2" smd circle
			(at -0.40005 0 90)
			(size 0 0)
			(layers "B.Cu" "B.Mask" "B.Paste")
			(net "SPI_BMC_BIOS_ROM_R_MISO")
		)
	)
	(footprint ""
		(layer "B.Cu")
		(at 77.2795 -99.911408)
		(property "Reference" "R713"
			(at 0 0 0)
			(layer "B.SilkS")
			(hide yes)
			(effects
				(font
					(size 1.27 1.27)
				)
				(justify mirror)
			)
		)
		(property "Value" ""
			(at 0 0 0)
			(layer "B.Fab")
			(effects
				(font
					(size 1.27 1.27)
				)
				(justify mirror)
			)
		)
		(duplicate_pad_numbers_are_jumpers no)
		(fp_line
			(start -0.7874 -0.4064)
			(end -0.7874 0.4064)
			(stroke
				(width 0.1524)
				(type default)
			)
			(layer "B.SilkS")
		)
		(fp_line
			(start -0.7874 0.4064)
			(end 0.7874 0.4064)
			(stroke
				(width 0.1524)
				(type default)
			)
			(layer "B.SilkS")
		)
		(fp_line
			(start 0.7874 -0.4064)
			(end -0.7874 -0.4064)
			(stroke
				(width 0.1524)
				(type default)
			)
			(layer "B.SilkS")
		)
		(fp_line
			(start 0.7874 0.4064)
			(end 0.7874 -0.4064)
			(stroke
				(width 0.1524)
				(type default)
			)
			(layer "B.SilkS")
		)
		(fp_line
			(start -0.67945 -0.3048)
			(end -0.67945 0.3048)
			(stroke
				(width 0.1)
				(type default)
			)
			(layer "B.Fab")
		)
		(fp_line
			(start -0.67945 0.3048)
			(end -0.120396 0.3048)
			(stroke
				(width 0.1)
				(type default)
			)
			(layer "B.Fab")
		)
		(fp_line
			(start -0.12065 -0.3048)
			(end -0.67945 -0.3048)
			(stroke
				(width 0.1)
				(type default)
			)
			(layer "B.Fab")
		)
		(fp_line
			(start -0.12065 -0.2794)
			(end -0.12065 -0.3048)
			(stroke
				(width 0.1)
				(type default)
			)
			(layer "B.Fab")
		)
		(fp_line
			(start -0.120396 0.2794)
			(end 0.12065 0.2794)
			(stroke
				(width 0.1)
				(type default)
			)
			(layer "B.Fab")
		)
		(fp_line
			(start -0.120396 0.3048)
			(end -0.120396 0.2794)
			(stroke
				(width 0.1)
				(type default)
			)
			(layer "B.Fab")
		)
		(fp_line
			(start 0.12065 -0.305054)
			(end 0.12065 -0.2794)
			(stroke
				(width 0.1)
				(type default)
			)
			(layer "B.Fab")
		)
		(fp_line
			(start 0.12065 -0.2794)
			(end -0.12065 -0.2794)
			(stroke
				(width 0.1)
				(type default)
			)
			(layer "B.Fab")
		)
		(fp_line
			(start 0.12065 0.2794)
			(end 0.12065 0.3048)
			(stroke
				(width 0.1)
				(type default)
			)
			(layer "B.Fab")
		)
		(fp_line
			(start 0.12065 0.3048)
			(end 0.67945 0.3048)
			(stroke
				(width 0.1)
				(type default)
			)
			(layer "B.Fab")
		)
		(fp_line
			(start 0.67945 -0.305054)
			(end 0.12065 -0.305054)
			(stroke
				(width 0.1)
				(type default)
			)
			(layer "B.Fab")
		)
		(fp_line
			(start 0.67945 0.3048)
			(end 0.67945 -0.305054)
			(stroke
				(width 0.1)
				(type default)
			)
			(layer "B.Fab")
		)
		(pad "1" smd circle
			(at 0.40005 0 180)
			(size 0 0)
			(layers "B.Cu" "B.Mask" "B.Paste")
			(net "LPC_ESPI_SEL_R")
		)
		(pad "2" smd circle
			(at -0.40005 0 180)
			(size 0 0)
			(layers "B.Cu" "B.Mask" "B.Paste")
			(net "LPC_ESPI_SEL")
		)
	)
	(footprint ""
		(layer "B.Cu")
		(at 55.705502 -30.867604 -90)
		(property "Reference" "R258"
			(at 0 0 90)
			(layer "B.SilkS")
			(hide yes)
			(effects
				(font
					(size 1.27 1.27)
				)
				(justify mirror)
			)
		)
		(property "Value" ""
			(at 0 0 90)
			(layer "B.Fab")
			(effects
				(font
					(size 1.27 1.27)
				)
				(justify mirror)
			)
		)
		(duplicate_pad_numbers_are_jumpers no)
		(fp_line
			(start -0.7874 0.4064)
			(end 0.7874 0.4064)
			(stroke
				(width 0.1524)
				(type default)
			)
			(layer "B.SilkS")
		)
		(fp_line
			(start 0.7874 0.4064)
			(end 0.7874 -0.4064)
			(stroke
				(width 0.1524)
				(type default)
			)
			(layer "B.SilkS")
		)
		(fp_line
			(start -0.7874 -0.4064)
			(end -0.7874 0.4064)
			(stroke
				(width 0.1524)
				(type default)
			)
			(layer "B.SilkS")
		)
		(fp_line
			(start 0.7874 -0.4064)
			(end -0.7874 -0.4064)
			(stroke
				(width 0.1524)
				(type default)
			)
			(layer "B.SilkS")
		)
		(fp_line
			(start -0.67945 0.3048)
			(end -0.120396 0.3048)
			(stroke
				(width 0.1)
				(type default)
			)
			(layer "B.Fab")
		)
		(fp_line
			(start -0.120396 0.3048)
			(end -0.120396 0.2794)
			(stroke
				(width 0.1)
				(type default)
			)
			(layer "B.Fab")
		)
		(fp_line
			(start 0.12065 0.3048)
			(end 0.67945 0.3048)
			(stroke
				(width 0.1)
				(type default)
			)
			(layer "B.Fab")
		)
		(fp_line
			(start 0.67945 0.3048)
			(end 0.67945 -0.305054)
			(stroke
				(width 0.1)
				(type default)
			)
			(layer "B.Fab")
		)
		(fp_line
			(start -0.120396 0.2794)
			(end 0.12065 0.2794)
			(stroke
				(width 0.1)
				(type default)
			)
			(layer "B.Fab")
		)
		(fp_line
			(start 0.12065 0.2794)
			(end 0.12065 0.3048)
			(stroke
				(width 0.1)
				(type default)
			)
			(layer "B.Fab")
		)
		(fp_line
			(start -0.12065 -0.2794)
			(end -0.12065 -0.3048)
			(stroke
				(width 0.1)
				(type default)
			)
			(layer "B.Fab")
		)
		(fp_line
			(start 0.12065 -0.2794)
			(end -0.12065 -0.2794)
			(stroke
				(width 0.1)
				(type default)
			)
			(layer "B.Fab")
		)
		(fp_line
			(start -0.67945 -0.3048)
			(end -0.67945 0.3048)
			(stroke
				(width 0.1)
				(type default)
			)
			(layer "B.Fab")
		)
		(fp_line
			(start -0.12065 -0.3048)
			(end -0.67945 -0.3048)
			(stroke
				(width 0.1)
				(type default)
			)
			(layer "B.Fab")
		)
		(fp_line
			(start 0.12065 -0.305054)
			(end 0.12065 -0.2794)
			(stroke
				(width 0.1)
				(type default)
			)
			(layer "B.Fab")
		)
		(fp_line
			(start 0.67945 -0.305054)
			(end 0.12065 -0.305054)
			(stroke
				(width 0.1)
				(type default)
			)
			(layer "B.Fab")
		)
		(pad "1" smd circle
			(at 0.40005 0 90)
			(size 0 0)
			(layers "B.Cu" "B.Mask" "B.Paste")
			(net "P3V3_AUX")
		)
		(pad "2" smd circle
			(at -0.40005 0 90)
			(size 0 0)
			(layers "B.Cu" "B.Mask" "B.Paste")
			(net "SMB_BMC_MM8_SCL")
		)
	)
	(footprint ""
		(layer "B.Cu")
		(at 37.6047 -92.2528 -90)
		(property "Reference" "C236"
			(at 0 0 90)
			(layer "B.SilkS")
			(hide yes)
			(effects
				(font
					(size 1.27 1.27)
				)
				(justify mirror)
			)
		)
		(property "Value" ""
			(at 0 0 90)
			(layer "B.Fab")
			(effects
				(font
					(size 1.27 1.27)
				)
				(justify mirror)
			)
		)
		(duplicate_pad_numbers_are_jumpers no)
		(fp_line
			(start -0.7874 0.4064)
			(end 0.7874 0.4064)
			(stroke
				(width 0.1524)
				(type default)
			)
			(layer "B.SilkS")
		)
		(fp_line
			(start 0.7874 0.4064)
			(end 0.7874 -0.4064)
			(stroke
				(width 0.1524)
				(type default)
			)
			(layer "B.SilkS")
		)
		(fp_line
			(start -0.7874 -0.4064)
			(end -0.7874 0.4064)
			(stroke
				(width 0.1524)
				(type default)
			)
			(layer "B.SilkS")
		)
		(fp_line
			(start 0.7874 -0.4064)
			(end -0.7874 -0.4064)
			(stroke
				(width 0.1524)
				(type default)
			)
			(layer "B.SilkS")
		)
		(fp_line
			(start -0.67945 0.3048)
			(end -0.120396 0.3048)
			(stroke
				(width 0.1)
				(type default)
			)
			(layer "B.Fab")
		)
		(fp_line
			(start -0.120396 0.3048)
			(end -0.120396 0.2794)
			(stroke
				(width 0.1)
				(type default)
			)
			(layer "B.Fab")
		)
		(fp_line
			(start 0.12065 0.3048)
			(end 0.67945 0.3048)
			(stroke
				(width 0.1)
				(type default)
			)
			(layer "B.Fab")
		)
		(fp_line
			(start 0.67945 0.3048)
			(end 0.67945 -0.305054)
			(stroke
				(width 0.1)
				(type default)
			)
			(layer "B.Fab")
		)
		(fp_line
			(start -0.120396 0.2794)
			(end 0.12065 0.2794)
			(stroke
				(width 0.1)
				(type default)
			)
			(layer "B.Fab")
		)
		(fp_line
			(start 0.12065 0.2794)
			(end 0.12065 0.3048)
			(stroke
				(width 0.1)
				(type default)
			)
			(layer "B.Fab")
		)
		(fp_line
			(start -0.12065 -0.2794)
			(end -0.12065 -0.3048)
			(stroke
				(width 0.1)
				(type default)
			)
			(layer "B.Fab")
		)
		(fp_line
			(start 0.12065 -0.2794)
			(end -0.12065 -0.2794)
			(stroke
				(width 0.1)
				(type default)
			)
			(layer "B.Fab")
		)
		(fp_line
			(start -0.67945 -0.3048)
			(end -0.67945 0.3048)
			(stroke
				(width 0.1)
				(type default)
			)
			(layer "B.Fab")
		)
		(fp_line
			(start -0.12065 -0.3048)
			(end -0.67945 -0.3048)
			(stroke
				(width 0.1)
				(type default)
			)
			(layer "B.Fab")
		)
		(fp_line
			(start 0.12065 -0.305054)
			(end 0.12065 -0.2794)
			(stroke
				(width 0.1)
				(type default)
			)
			(layer "B.Fab")
		)
		(fp_line
			(start 0.67945 -0.305054)
			(end 0.12065 -0.305054)
			(stroke
				(width 0.1)
				(type default)
			)
			(layer "B.Fab")
		)
		(pad "1" smd circle
			(at 0.40005 0 90)
			(size 0 0)
			(layers "B.Cu" "B.Mask" "B.Paste")
			(net "P3V3_AUX")
		)
		(pad "2" smd circle
			(at -0.40005 0 90)
			(size 0 0)
			(layers "B.Cu" "B.Mask" "B.Paste")
			(net "GND")
		)
	)
)
